(kicad_pcb
	(version 20260206)
	(generator "pcbnew")
	(generator_version "10.0")
	(general
		(thickness 1.6)
		(legacy_teardrops no)
	)
	(paper "A4")
	(title_block
		(title "peb — Lightning_PEB_BRD.brd")
		(comment 1 "Lightning (Wiwynn / Facebook NVMe JBOF) / footprints 1807-1815 of 2563")
	)
	(layers
		(0 "F.Cu" signal "TOP")
		(4 "In1.Cu" signal "L2GND")
		(6 "In2.Cu" signal "L3")
		(8 "In3.Cu" signal "L4VCC")
		(10 "In4.Cu" signal "L5VCC")
		(12 "In5.Cu" signal "L6")
		(14 "In6.Cu" signal "L7GND")
		(2 "B.Cu" signal "BOTTOM")
		(9 "F.Adhes" user "F.Adhesive")
		(11 "B.Adhes" user "B.Adhesive")
		(13 "F.Paste" user "Package Geometry/Pastemask Top")
		(15 "B.Paste" user "Package Geometry/Pastemask Bottom")
		(5 "F.SilkS" user "Ref Des/Silkscreen Top")
		(7 "B.SilkS" user "Ref Des/Silkscreen Bottom")
		(1 "F.Mask" user "Board Geometry/Soldermask Top")
		(3 "B.Mask" user "Board Geometry/Soldermask Bottom")
		(17 "Dwgs.User" user "User.Drawings")
		(19 "Cmts.User" user "User.Comments")
		(21 "Eco1.User" user "User.Eco1")
		(23 "Eco2.User" user "User.Eco2")
		(25 "Edge.Cuts" user "Board Geometry/Outline")
		(27 "Margin" user)
		(31 "F.CrtYd" user "Package Geometry/Place Bound Top")
		(29 "B.CrtYd" user "Package Geometry/Place Bound Bottom")
		(35 "F.Fab" user "Ref Des/Assembly Top")
		(33 "B.Fab" user "Ref Des/Assembly Bottom")
	)
	(footprint ""
		(layer "B.Cu")
		(at 321.673728 -36.991036 180)
		(property "Reference" "C242"
			(at 0 0 0)
			(layer "B.SilkS")
			(hide yes)
			(effects
				(font
					(size 1.27 1.27)
				)
				(justify mirror)
			)
		)
		(property "Value" "SCD1U10V2KX-5GP"
			(at -1.1811 -2.7051 180)
			(unlocked yes)
			(layer "B.Fab")
			(hide yes)
			(effects
				(font
					(size 1.016 1.016)
					(thickness 0.1524)
				)
				(justify mirror)
			)
		)
		(property "Device Type" "C402H22"
			(at -1.1811 -4.2291 180)
			(unlocked yes)
			(layer "B.Fab")
			(hide yes)
			(effects
				(font
					(size 1.016 1.016)
					(thickness 0.1524)
				)
				(justify mirror)
			)
		)
		(duplicate_pad_numbers_are_jumpers no)
		(fp_rect
			(start 0.4318 0.9525)
			(end -0.4318 -0.9525)
			(stroke
				(width 0)
				(type default)
			)
			(fill no)
			(layer "B.CrtYd")
		)
		(fp_rect
			(start 0.4318 0.9525)
			(end -0.4318 -0.9525)
			(stroke
				(width 0)
				(type default)
			)
			(fill no)
			(layer "B.Fab")
		)
		(pad "1" smd custom
			(at 0 -0.4445)
			(size 0.1524 0.1524)
			(layers "B.Cu" "B.Mask" "B.Paste")
			(net "GND")
			(options
				(clearance outline)
				(anchor circle)
			)
			(primitives
				(gr_poly
					(pts
						(arc
							(start 0.3048 0.2032)
							(mid 0.275042 0.275042)
							(end 0.2032 0.3048)
						)
						(arc
							(start -0.2032 0.3048)
							(mid -0.275042 0.275042)
							(end -0.3048 0.2032)
						)
						(arc
							(start -0.3048 -0.2032)
							(mid -0.275042 -0.275042)
							(end -0.2032 -0.3048)
						)
						(arc
							(start 0.2032 -0.3048)
							(mid 0.275042 -0.275042)
							(end 0.3048 -0.2032)
						)
					)
					(width 0)
					(fill yes)
				)
			)
		)
		(pad "2" smd custom
			(at 0 0.4445)
			(size 0.1524 0.1524)
			(layers "B.Cu" "B.Mask" "B.Paste")
			(net "P3V3_STBY")
			(options
				(clearance outline)
				(anchor circle)
			)
			(primitives
				(gr_poly
					(pts
						(arc
							(start 0.3048 0.2032)
							(mid 0.275042 0.275042)
							(end 0.2032 0.3048)
						)
						(arc
							(start -0.2032 0.3048)
							(mid -0.275042 0.275042)
							(end -0.3048 0.2032)
						)
						(arc
							(start -0.3048 -0.2032)
							(mid -0.275042 -0.275042)
							(end -0.2032 -0.3048)
						)
						(arc
							(start 0.2032 -0.3048)
							(mid 0.275042 -0.275042)
							(end 0.3048 -0.2032)
						)
					)
					(width 0)
					(fill yes)
				)
			)
		)
	)
	(footprint ""
		(layer "B.Cu")
		(at 64.135 -44.958 90)
		(property "Reference" "PC23"
			(at 0 0 90)
			(layer "B.SilkS")
			(hide yes)
			(effects
				(font
					(size 1.27 1.27)
				)
				(justify mirror)
			)
		)
		(property "Value" "SC10U25V5KX-GP"
			(at 0.0762 -6.1214 90)
			(unlocked yes)
			(layer "B.Fab")
			(hide yes)
			(effects
				(font
					(size 1.016 1.016)
					(thickness 0.1524)
				)
				(justify mirror)
			)
		)
		(property "Device Type" "C805H56"
			(at 0.0762 -8.1534 90)
			(unlocked yes)
			(layer "B.Fab")
			(hide yes)
			(effects
				(font
					(size 1.016 1.016)
					(thickness 0.1524)
				)
				(justify mirror)
			)
		)
		(duplicate_pad_numbers_are_jumpers no)
		(fp_line
			(start -0.635 0)
			(end 0.635 0)
			(stroke
				(width 0.508)
				(type default)
			)
			(layer "B.SilkS")
		)
		(fp_rect
			(start 0.9652 1.778)
			(end -0.9652 -1.778)
			(stroke
				(width 0)
				(type default)
			)
			(fill no)
			(layer "B.CrtYd")
		)
		(fp_poly
			(pts
				(xy 0.9652 -1.778) (xy -0.9652 -1.778) (xy -0.9652 1.778) (xy 0.9652 1.778)
			)
			(stroke
				(width 0)
				(type default)
			)
			(fill no)
			(layer "B.Fab")
		)
		(pad "1" smd rect
			(at 0 -0.9652 270)
			(size 1.397 1.143)
			(layers "B.Cu" "B.Mask" "B.Paste")
			(net "P3V3_STBY_VIN")
		)
		(pad "2" smd rect
			(at 0 0.9652 270)
			(size 1.397 1.143)
			(layers "B.Cu" "B.Mask" "B.Paste")
			(net "GND")
		)
	)
	(footprint ""
		(layer "B.Cu")
		(at 64.135 -121.285 90)
		(property "Reference" "R244"
			(at 0 0 90)
			(layer "B.SilkS")
			(hide yes)
			(effects
				(font
					(size 1.27 1.27)
				)
				(justify mirror)
			)
		)
		(property "Value" "0R2J-2-GP"
			(at -0.064008 -3.993896 90)
			(unlocked yes)
			(layer "B.Fab")
			(hide yes)
			(effects
				(font
					(size 1.016 1.016)
					(thickness 0.1524)
				)
				(justify mirror)
			)
		)
		(property "Device Type" "R402H16"
			(at -0.064008 -5.517896 90)
			(unlocked yes)
			(layer "B.Fab")
			(hide yes)
			(effects
				(font
					(size 1.016 1.016)
					(thickness 0.1524)
				)
				(justify mirror)
			)
		)
		(duplicate_pad_numbers_are_jumpers no)
		(fp_line
			(start 0.508 -0.9398)
			(end 0.508 0.9398)
			(stroke
				(width 0.1524)
				(type default)
			)
			(layer "B.SilkS")
		)
		(fp_line
			(start -0.508 -0.9398)
			(end 0.508 -0.9398)
			(stroke
				(width 0.1524)
				(type default)
			)
			(layer "B.SilkS")
		)
		(fp_rect
			(start 0.508 0.9398)
			(end -0.508 -0.9398)
			(stroke
				(width 0)
				(type default)
			)
			(fill no)
			(layer "B.CrtYd")
		)
		(fp_rect
			(start 0.508 0.9398)
			(end -0.508 -0.9398)
			(stroke
				(width 0)
				(type default)
			)
			(fill no)
			(layer "B.Fab")
		)
		(pad "1" smd custom
			(at 0 -0.4445 270)
			(size 0.1397 0.1397)
			(layers "B.Cu" "B.Mask" "B.Paste")
			(net "BMC_I2C4_MINI4_SCL_S")
			(options
				(clearance outline)
				(anchor circle)
			)
			(primitives
				(gr_poly
					(pts
						(arc
							(start -0.1778 0.2794)
							(mid -0.249642 0.249642)
							(end -0.2794 0.1778)
						)
						(arc
							(start -0.2794 -0.1778)
							(mid -0.249642 -0.249642)
							(end -0.1778 -0.2794)
						)
						(arc
							(start 0.1778 -0.2794)
							(mid 0.249642 -0.249642)
							(end 0.2794 -0.1778)
						)
						(arc
							(start 0.2794 0.1778)
							(mid 0.249642 0.249642)
							(end 0.1778 0.2794)
						)
					)
					(width 0)
					(fill yes)
				)
			)
		)
		(pad "2" smd custom
			(at 0 0.4445 270)
			(size 0.1397 0.1397)
			(layers "B.Cu" "B.Mask" "B.Paste")
			(net "BMC0_SMB4_CLK")
			(options
				(clearance outline)
				(anchor circle)
			)
			(primitives
				(gr_poly
					(pts
						(arc
							(start -0.1778 0.2794)
							(mid -0.249642 0.249642)
							(end -0.2794 0.1778)
						)
						(arc
							(start -0.2794 -0.1778)
							(mid -0.249642 -0.249642)
							(end -0.1778 -0.2794)
						)
						(arc
							(start 0.1778 -0.2794)
							(mid 0.249642 -0.249642)
							(end 0.2794 -0.1778)
						)
						(arc
							(start 0.2794 0.1778)
							(mid 0.249642 0.249642)
							(end 0.1778 0.2794)
						)
					)
					(width 0)
					(fill yes)
				)
			)
		)
	)
	(footprint ""
		(layer "B.Cu")
		(at 169.967402 -62.714632)
		(property "Reference" "PC209"
			(at 0 0 0)
			(layer "B.SilkS")
			(hide yes)
			(effects
				(font
					(size 1.27 1.27)
				)
				(justify mirror)
			)
		)
		(property "Value" "SC22U6D3V5MX-5-GP"
			(at 0.0762 -6.1214 0)
			(unlocked yes)
			(layer "B.Fab")
			(hide yes)
			(effects
				(font
					(size 1.016 1.016)
					(thickness 0.1524)
				)
				(justify mirror)
			)
		)
		(property "Device Type" "C805H56"
			(at 0.0762 -8.1534 0)
			(unlocked yes)
			(layer "B.Fab")
			(hide yes)
			(effects
				(font
					(size 1.016 1.016)
					(thickness 0.1524)
				)
				(justify mirror)
			)
		)
		(duplicate_pad_numbers_are_jumpers no)
		(fp_line
			(start -0.635 0)
			(end 0.635 0)
			(stroke
				(width 0.508)
				(type default)
			)
			(layer "B.SilkS")
		)
		(fp_rect
			(start 0.9652 1.778)
			(end -0.9652 -1.778)
			(stroke
				(width 0)
				(type default)
			)
			(fill no)
			(layer "B.CrtYd")
		)
		(fp_poly
			(pts
				(xy 0.9652 -1.778) (xy -0.9652 -1.778) (xy -0.9652 1.778) (xy 0.9652 1.778)
			)
			(stroke
				(width 0)
				(type default)
			)
			(fill no)
			(layer "B.Fab")
		)
		(pad "1" smd rect
			(at 0 -0.9652 180)
			(size 1.397 1.143)
			(layers "B.Cu" "B.Mask" "B.Paste")
			(net "P0V9")
		)
		(pad "2" smd rect
			(at 0 0.9652 180)
			(size 1.397 1.143)
			(layers "B.Cu" "B.Mask" "B.Paste")
			(net "GND")
		)
	)
	(footprint ""
		(layer "B.Cu")
		(at 178.0794 -66.929)
		(property "Reference" "PG24"
			(at 0 0 0)
			(layer "B.SilkS")
			(hide yes)
			(effects
				(font
					(size 1.27 1.27)
				)
				(justify mirror)
			)
		)
		(property "Value" "GAP-CLOSE-PWR-3-GP"
			(at -0.0254 -6.5786 0)
			(unlocked yes)
			(layer "B.Fab")
			(hide yes)
			(effects
				(font
					(size 1.016 1.016)
					(thickness 0.1524)
				)
				(justify mirror)
			)
		)
		(property "Device Type" "GAP-CLOSE-PWR-3"
			(at -0.0254 -8.255 0)
			(unlocked yes)
			(layer "B.Fab")
			(hide yes)
			(effects
				(font
					(size 1.016 1.016)
					(thickness 0.1524)
				)
				(justify mirror)
			)
		)
		(duplicate_pad_numbers_are_jumpers no)
		(fp_rect
			(start 0.7112 0.4572)
			(end -0.7112 -0.4572)
			(stroke
				(width 0)
				(type default)
			)
			(fill no)
			(layer "B.CrtYd")
		)
		(fp_poly
			(pts
				(xy 0.7112 -0.4572) (xy -0.7112 -0.4572) (xy -0.7112 0.4572) (xy 0.7112 0.4572)
			)
			(stroke
				(width 0)
				(type default)
			)
			(fill no)
			(layer "B.Fab")
		)
		(pad "1" smd rect
			(at 0.3048 0 180)
			(size 0.6604 0.762)
			(layers "B.Cu" "B.Mask" "B.Paste")
			(net "DUT_AVD_PCIE")
		)
		(pad "2" smd rect
			(at -0.3048 0 180)
			(size 0.6604 0.762)
			(layers "B.Cu" "B.Mask" "B.Paste")
			(net "P0V9")
		)
	)
	(footprint ""
		(layer "B.Cu")
		(at 123.928124 -196.443092 180)
		(property "Reference" "R536"
			(at 0 0 0)
			(layer "B.SilkS")
			(hide yes)
			(effects
				(font
					(size 1.27 1.27)
				)
				(justify mirror)
			)
		)
		(property "Value" "10KR2F-2-GP"
			(at -0.064008 -3.993896 180)
			(unlocked yes)
			(layer "B.Fab")
			(hide yes)
			(effects
				(font
					(size 1.016 1.016)
					(thickness 0.1524)
				)
				(justify mirror)
			)
		)
		(property "Device Type" "R402H16"
			(at -0.064008 -5.517896 180)
			(unlocked yes)
			(layer "B.Fab")
			(hide yes)
			(effects
				(font
					(size 1.016 1.016)
					(thickness 0.1524)
				)
				(justify mirror)
			)
		)
		(duplicate_pad_numbers_are_jumpers no)
		(fp_line
			(start 0.508 -0.9398)
			(end 0.508 0.9398)
			(stroke
				(width 0.1524)
				(type default)
			)
			(layer "B.SilkS")
		)
		(fp_line
			(start -0.508 -0.9398)
			(end 0.508 -0.9398)
			(stroke
				(width 0.1524)
				(type default)
			)
			(layer "B.SilkS")
		)
		(fp_rect
			(start 0.508 0.9398)
			(end -0.508 -0.9398)
			(stroke
				(width 0)
				(type default)
			)
			(fill no)
			(layer "B.CrtYd")
		)
		(fp_rect
			(start 0.508 0.9398)
			(end -0.508 -0.9398)
			(stroke
				(width 0)
				(type default)
			)
			(fill no)
			(layer "B.Fab")
		)
		(pad "1" smd custom
			(at 0 -0.4445)
			(size 0.1397 0.1397)
			(layers "B.Cu" "B.Mask" "B.Paste")
			(net "P3V3_STBY")
			(options
				(clearance outline)
				(anchor circle)
			)
			(primitives
				(gr_poly
					(pts
						(arc
							(start -0.1778 0.2794)
							(mid -0.249642 0.249642)
							(end -0.2794 0.1778)
						)
						(arc
							(start -0.2794 -0.1778)
							(mid -0.249642 -0.249642)
							(end -0.1778 -0.2794)
						)
						(arc
							(start 0.1778 -0.2794)
							(mid 0.249642 -0.249642)
							(end 0.2794 -0.1778)
						)
						(arc
							(start 0.2794 0.1778)
							(mid 0.249642 0.249642)
							(end 0.1778 0.2794)
						)
					)
					(width 0)
					(fill yes)
				)
			)
		)
		(pad "2" smd custom
			(at 0 0.4445)
			(size 0.1397 0.1397)
			(layers "B.Cu" "B.Mask" "B.Paste")
			(net "IOEXP2_AD1")
			(options
				(clearance outline)
				(anchor circle)
			)
			(primitives
				(gr_poly
					(pts
						(arc
							(start -0.1778 0.2794)
							(mid -0.249642 0.249642)
							(end -0.2794 0.1778)
						)
						(arc
							(start -0.2794 -0.1778)
							(mid -0.249642 -0.249642)
							(end -0.1778 -0.2794)
						)
						(arc
							(start 0.1778 -0.2794)
							(mid 0.249642 -0.249642)
							(end 0.2794 -0.1778)
						)
						(arc
							(start 0.2794 0.1778)
							(mid 0.249642 0.249642)
							(end 0.1778 0.2794)
						)
					)
					(width 0)
					(fill yes)
				)
			)
		)
	)
	(footprint ""
		(layer "B.Cu")
		(at 28.702 -116.967)
		(property "Reference" "R705"
			(at 0 0 0)
			(layer "B.SilkS")
			(hide yes)
			(effects
				(font
					(size 1.27 1.27)
				)
				(justify mirror)
			)
		)
		(property "Value" "0R2J-2-GP"
			(at -0.064008 -3.993896 0)
			(unlocked yes)
			(layer "B.Fab")
			(hide yes)
			(effects
				(font
					(size 1.016 1.016)
					(thickness 0.1524)
				)
				(justify mirror)
			)
		)
		(property "Device Type" "R402H16"
			(at -0.064008 -5.517896 0)
			(unlocked yes)
			(layer "B.Fab")
			(hide yes)
			(effects
				(font
					(size 1.016 1.016)
					(thickness 0.1524)
				)
				(justify mirror)
			)
		)
		(duplicate_pad_numbers_are_jumpers no)
		(fp_line
			(start -0.508 -0.9398)
			(end 0.508 -0.9398)
			(stroke
				(width 0.1524)
				(type default)
			)
			(layer "B.SilkS")
		)
		(fp_line
			(start 0.508 -0.9398)
			(end 0.508 0.9398)
			(stroke
				(width 0.1524)
				(type default)
			)
			(layer "B.SilkS")
		)
		(fp_rect
			(start 0.508 0.9398)
			(end -0.508 -0.9398)
			(stroke
				(width 0)
				(type default)
			)
			(fill no)
			(layer "B.CrtYd")
		)
		(fp_rect
			(start 0.508 0.9398)
			(end -0.508 -0.9398)
			(stroke
				(width 0)
				(type default)
			)
			(fill no)
			(layer "B.Fab")
		)
		(pad "1" smd custom
			(at 0 -0.4445 180)
			(size 0.1397 0.1397)
			(layers "B.Cu" "B.Mask" "B.Paste")
			(net "SPIDO_R")
			(options
				(clearance outline)
				(anchor circle)
			)
			(primitives
				(gr_poly
					(pts
						(arc
							(start -0.1778 0.2794)
							(mid -0.249642 0.249642)
							(end -0.2794 0.1778)
						)
						(arc
							(start -0.2794 -0.1778)
							(mid -0.249642 -0.249642)
							(end -0.1778 -0.2794)
						)
						(arc
							(start 0.1778 -0.2794)
							(mid 0.249642 -0.249642)
							(end 0.2794 -0.1778)
						)
						(arc
							(start 0.2794 0.1778)
							(mid 0.249642 0.249642)
							(end 0.1778 0.2794)
						)
					)
					(width 0)
					(fill yes)
				)
			)
		)
		(pad "2" smd custom
			(at 0 0.4445 180)
			(size 0.1397 0.1397)
			(layers "B.Cu" "B.Mask" "B.Paste")
			(net "SPIDO")
			(options
				(clearance outline)
				(anchor circle)
			)
			(primitives
				(gr_poly
					(pts
						(arc
							(start -0.1778 0.2794)
							(mid -0.249642 0.249642)
							(end -0.2794 0.1778)
						)
						(arc
							(start -0.2794 -0.1778)
							(mid -0.249642 -0.249642)
							(end -0.1778 -0.2794)
						)
						(arc
							(start 0.1778 -0.2794)
							(mid 0.249642 -0.249642)
							(end 0.2794 -0.1778)
						)
						(arc
							(start 0.2794 0.1778)
							(mid 0.249642 0.249642)
							(end 0.1778 0.2794)
						)
					)
					(width 0)
					(fill yes)
				)
			)
		)
	)
	(footprint ""
		(layer "B.Cu")
		(at 249.599958 -33.999932 -90)
		(property "Reference" "TP208"
			(at 0 0 90)
			(layer "B.SilkS")
			(hide yes)
			(effects
				(font
					(size 1.27 1.27)
				)
				(justify mirror)
			)
		)
		(property "Value" "TPAD28-2-GP"
			(at 0.0127 -1.6637 270)
			(unlocked yes)
			(layer "B.Fab")
			(hide yes)
			(effects
				(font
					(size 1.016 1.016)
					(thickness 0.1524)
				)
				(justify mirror)
			)
		)
		(property "Device Type" "TPAD28"
			(at 0.0127 -3.1877 270)
			(unlocked yes)
			(layer "B.Fab")
			(hide yes)
			(effects
				(font
					(size 1.016 1.016)
					(thickness 0.1524)
				)
				(justify mirror)
			)
		)
		(duplicate_pad_numbers_are_jumpers no)
		(fp_poly
			(pts
				(arc
					(start 0 -0.3556)
					(mid 0 0.3556)
					(end 0 -0.3556)
				)
			)
			(stroke
				(width 0)
				(type default)
			)
			(fill no)
			(layer "B.CrtYd")
		)
		(fp_poly
			(pts
				(arc
					(start 0 -0.6096)
					(mid 0 0.6096)
					(end 0 -0.6096)
				)
			)
			(stroke
				(width 0)
				(type default)
			)
			(fill no)
			(layer "B.Fab")
		)
		(pad "1" smd circle
			(at 0 0 90)
			(size 0.7112 0.7112)
			(layers "B.Cu" "B.Mask" "B.Paste")
			(net "GPIO109_R")
		)
	)
	(footprint ""
		(layer "B.Cu")
		(at 310.007 -59.309 180)
		(property "Reference" "PG41"
			(at 0 0 0)
			(layer "B.SilkS")
			(hide yes)
			(effects
				(font
					(size 1.27 1.27)
				)
				(justify mirror)
			)
		)
		(property "Value" "GAP-CLOSE-PWR-3-GP"
			(at -0.0254 -6.5786 180)
			(unlocked yes)
			(layer "B.Fab")
			(hide yes)
			(effects
				(font
					(size 1.016 1.016)
					(thickness 0.1524)
				)
				(justify mirror)
			)
		)
		(property "Device Type" "GAP-CLOSE-PWR-3"
			(at -0.0254 -8.255 180)
			(unlocked yes)
			(layer "B.Fab")
			(hide yes)
			(effects
				(font
					(size 1.016 1.016)
					(thickness 0.1524)
				)
				(justify mirror)
			)
		)
		(duplicate_pad_numbers_are_jumpers no)
		(fp_rect
			(start 0.7112 0.4572)
			(end -0.7112 -0.4572)
			(stroke
				(width 0)
				(type default)
			)
			(fill no)
			(layer "B.CrtYd")
		)
		(fp_poly
			(pts
				(xy 0.7112 -0.4572) (xy -0.7112 -0.4572) (xy -0.7112 0.4572) (xy 0.7112 0.4572)
			)
			(stroke
				(width 0)
				(type default)
			)
			(fill no)
			(layer "B.Fab")
		)
		(pad "1" smd rect
			(at 0.3048 0)
			(size 0.6604 0.762)
			(layers "B.Cu" "B.Mask" "B.Paste")
			(net "DUT_VDD")
		)
		(pad "2" smd rect
			(at -0.3048 0)
			(size 0.6604 0.762)
			(layers "B.Cu" "B.Mask" "B.Paste")
			(net "P0V9_E")
		)
	)
)
